(kicad_pcb
	(version 20260206)
	(generator "pcbnew")
	(generator_version "10.0")
	(general
		(thickness 1.6)
		(legacy_teardrops no)
	)
	(paper "A4")
	(title_block
		(title "Bryce Canyon_IOM_IOC_16318-2_OCP.brd")
		(comment 1 "Bryce Canyon / footprints 52-59 of 1605")
	)
	(layers
		(0 "F.Cu" signal "TOP")
		(4 "In1.Cu" signal "L2GND")
		(6 "In2.Cu" signal "L3")
		(8 "In3.Cu" signal "L4VCC")
		(10 "In4.Cu" signal "L5VCC")
		(12 "In5.Cu" signal "L6")
		(14 "In6.Cu" signal "L7GND")
		(2 "B.Cu" signal "BOTTOM")
		(9 "F.Adhes" user "F.Adhesive")
		(11 "B.Adhes" user "B.Adhesive")
		(13 "F.Paste" user "Package Geometry/Pastemask Top")
		(15 "B.Paste" user "Package Geometry/Pastemask Bottom")
		(5 "F.SilkS" user "Ref Des/Silkscreen Top")
		(7 "B.SilkS" user "Ref Des/Silkscreen Bottom")
		(1 "F.Mask" user "Board Geometry/Soldermask Top")
		(3 "B.Mask" user "Board Geometry/Soldermask Bottom")
		(17 "Dwgs.User" user "User.Drawings")
		(19 "Cmts.User" user "User.Comments")
		(21 "Eco1.User" user "User.Eco1")
		(23 "Eco2.User" user "User.Eco2")
		(25 "Edge.Cuts" user "Board Geometry/Outline")
		(27 "Margin" user)
		(31 "F.CrtYd" user "Package Geometry/Place Bound Top")
		(29 "B.CrtYd" user "Package Geometry/Place Bound Bottom")
		(35 "F.Fab" user "Ref Des/Assembly Top")
		(33 "B.Fab" user "Ref Des/Assembly Bottom")
	)
	(footprint ""
		(layer "F.Cu")
		(at 61.28258 -141.391132 -90)
		(property "Reference" "R176"
			(at 0 0 270)
			(layer "F.SilkS")
			(hide yes)
			(effects
				(font
					(size 1.27 1.27)
				)
			)
		)
		(property "Value" "0R2J-2-GP"
			(at 0.064008 -3.993896 270)
			(unlocked yes)
			(layer "F.Fab")
			(hide yes)
			(effects
				(font
					(size 1.016 1.016)
					(thickness 0.1524)
				)
			)
		)
		(property "Device Type" "R402H16"
			(at 0.064008 -5.517896 270)
			(unlocked yes)
			(layer "F.Fab")
			(hide yes)
			(effects
				(font
					(size 1.016 1.016)
					(thickness 0.1524)
				)
			)
		)
		(duplicate_pad_numbers_are_jumpers no)
		(fp_line
			(start -0.508 -0.9398)
			(end -0.508 0.9398)
			(stroke
				(width 0.1524)
				(type default)
			)
			(layer "F.SilkS")
		)
		(fp_line
			(start 0.508 -0.9398)
			(end -0.508 -0.9398)
			(stroke
				(width 0.1524)
				(type default)
			)
			(layer "F.SilkS")
		)
		(fp_rect
			(start -0.508 0.9398)
			(end 0.508 -0.9398)
			(stroke
				(width 0)
				(type default)
			)
			(fill no)
			(layer "F.CrtYd")
		)
		(fp_rect
			(start -0.508 0.9398)
			(end 0.508 -0.9398)
			(stroke
				(width 0)
				(type default)
			)
			(fill no)
			(layer "F.Fab")
		)
		(pad "1" smd custom
			(at 0 -0.4445 270)
			(size 0.1397 0.1397)
			(layers "F.Cu" "F.Mask" "F.Paste")
			(net "I2C_M2_2_SDA")
			(options
				(clearance outline)
				(anchor circle)
			)
			(primitives
				(gr_poly
					(pts
						(arc
							(start -0.1778 -0.2794)
							(mid -0.249642 -0.249642)
							(end -0.2794 -0.1778)
						)
						(arc
							(start -0.2794 0.1778)
							(mid -0.249642 0.249642)
							(end -0.1778 0.2794)
						)
						(arc
							(start 0.1778 0.2794)
							(mid 0.249642 0.249642)
							(end 0.2794 0.1778)
						)
						(arc
							(start 0.2794 -0.1778)
							(mid 0.249642 -0.249642)
							(end 0.1778 -0.2794)
						)
					)
					(width 0)
					(fill yes)
				)
			)
		)
		(pad "2" smd custom
			(at 0 0.4445 270)
			(size 0.1397 0.1397)
			(layers "F.Cu" "F.Mask" "F.Paste")
			(net "BMC_SMB9_DAT")
			(options
				(clearance outline)
				(anchor circle)
			)
			(primitives
				(gr_poly
					(pts
						(arc
							(start -0.1778 -0.2794)
							(mid -0.249642 -0.249642)
							(end -0.2794 -0.1778)
						)
						(arc
							(start -0.2794 0.1778)
							(mid -0.249642 0.249642)
							(end -0.1778 0.2794)
						)
						(arc
							(start 0.1778 0.2794)
							(mid 0.249642 0.249642)
							(end 0.2794 0.1778)
						)
						(arc
							(start 0.2794 -0.1778)
							(mid 0.249642 -0.249642)
							(end 0.1778 -0.2794)
						)
					)
					(width 0)
					(fill yes)
				)
			)
		)
	)
	(footprint ""
		(layer "F.Cu")
		(at 43.9166 -157.9118)
		(property "Reference" "R174"
			(at 0 0 0)
			(layer "F.SilkS")
			(hide yes)
			(effects
				(font
					(size 1.27 1.27)
				)
			)
		)
		(property "Value" "0R2J-2-GP"
			(at 0.064008 -3.993896 0)
			(unlocked yes)
			(layer "F.Fab")
			(hide yes)
			(effects
				(font
					(size 1.016 1.016)
					(thickness 0.1524)
				)
			)
		)
		(property "Device Type" "R402H16"
			(at 0.064008 -5.517896 0)
			(unlocked yes)
			(layer "F.Fab")
			(hide yes)
			(effects
				(font
					(size 1.016 1.016)
					(thickness 0.1524)
				)
			)
		)
		(duplicate_pad_numbers_are_jumpers no)
		(fp_line
			(start -0.508 -0.9398)
			(end -0.508 0.9398)
			(stroke
				(width 0.1524)
				(type default)
			)
			(layer "F.SilkS")
		)
		(fp_line
			(start 0.508 -0.9398)
			(end -0.508 -0.9398)
			(stroke
				(width 0.1524)
				(type default)
			)
			(layer "F.SilkS")
		)
		(fp_rect
			(start -0.508 0.9398)
			(end 0.508 -0.9398)
			(stroke
				(width 0)
				(type default)
			)
			(fill no)
			(layer "F.CrtYd")
		)
		(fp_rect
			(start -0.508 0.9398)
			(end 0.508 -0.9398)
			(stroke
				(width 0)
				(type default)
			)
			(fill no)
			(layer "F.Fab")
		)
		(pad "1" smd custom
			(at 0 -0.4445)
			(size 0.1397 0.1397)
			(layers "F.Cu" "F.Mask" "F.Paste")
			(net "I2C_M2_1_SDA")
			(options
				(clearance outline)
				(anchor circle)
			)
			(primitives
				(gr_poly
					(pts
						(arc
							(start -0.1778 -0.2794)
							(mid -0.249642 -0.249642)
							(end -0.2794 -0.1778)
						)
						(arc
							(start -0.2794 0.1778)
							(mid -0.249642 0.249642)
							(end -0.1778 0.2794)
						)
						(arc
							(start 0.1778 0.2794)
							(mid 0.249642 0.249642)
							(end 0.2794 0.1778)
						)
						(arc
							(start 0.2794 -0.1778)
							(mid 0.249642 -0.249642)
							(end 0.1778 -0.2794)
						)
					)
					(width 0)
					(fill yes)
				)
			)
		)
		(pad "2" smd custom
			(at 0 0.4445)
			(size 0.1397 0.1397)
			(layers "F.Cu" "F.Mask" "F.Paste")
			(net "BMC_SMB8_DAT")
			(options
				(clearance outline)
				(anchor circle)
			)
			(primitives
				(gr_poly
					(pts
						(arc
							(start -0.1778 -0.2794)
							(mid -0.249642 -0.249642)
							(end -0.2794 -0.1778)
						)
						(arc
							(start -0.2794 0.1778)
							(mid -0.249642 0.249642)
							(end -0.1778 0.2794)
						)
						(arc
							(start 0.1778 0.2794)
							(mid 0.249642 0.249642)
							(end 0.2794 0.1778)
						)
						(arc
							(start 0.2794 -0.1778)
							(mid 0.249642 -0.249642)
							(end 0.1778 -0.2794)
						)
					)
					(width 0)
					(fill yes)
				)
			)
		)
	)
	(footprint ""
		(layer "F.Cu")
		(at 182.372 -88.392)
		(property "Reference" "R621"
			(at 0 0 0)
			(layer "F.SilkS")
			(hide yes)
			(effects
				(font
					(size 1.27 1.27)
				)
			)
		)
		(property "Value" "4K7R2F-GP"
			(at 0.064008 -3.993896 0)
			(unlocked yes)
			(layer "F.Fab")
			(hide yes)
			(effects
				(font
					(size 1.016 1.016)
					(thickness 0.1524)
				)
			)
		)
		(property "Device Type" "R402H16"
			(at 0.064008 -5.517896 0)
			(unlocked yes)
			(layer "F.Fab")
			(hide yes)
			(effects
				(font
					(size 1.016 1.016)
					(thickness 0.1524)
				)
			)
		)
		(duplicate_pad_numbers_are_jumpers no)
		(fp_line
			(start -0.508 -0.9398)
			(end -0.508 0.9398)
			(stroke
				(width 0.1524)
				(type default)
			)
			(layer "F.SilkS")
		)
		(fp_line
			(start 0.508 -0.9398)
			(end -0.508 -0.9398)
			(stroke
				(width 0.1524)
				(type default)
			)
			(layer "F.SilkS")
		)
		(fp_rect
			(start -0.508 0.9398)
			(end 0.508 -0.9398)
			(stroke
				(width 0)
				(type default)
			)
			(fill no)
			(layer "F.CrtYd")
		)
		(fp_rect
			(start -0.508 0.9398)
			(end 0.508 -0.9398)
			(stroke
				(width 0)
				(type default)
			)
			(fill no)
			(layer "F.Fab")
		)
		(pad "1" smd custom
			(at 0 -0.4445)
			(size 0.1397 0.1397)
			(layers "F.Cu" "F.Mask" "F.Paste")
			(net "P1V8")
			(options
				(clearance outline)
				(anchor circle)
			)
			(primitives
				(gr_poly
					(pts
						(arc
							(start -0.1778 -0.2794)
							(mid -0.249642 -0.249642)
							(end -0.2794 -0.1778)
						)
						(arc
							(start -0.2794 0.1778)
							(mid -0.249642 0.249642)
							(end -0.1778 0.2794)
						)
						(arc
							(start 0.1778 0.2794)
							(mid 0.249642 0.249642)
							(end 0.2794 0.1778)
						)
						(arc
							(start 0.2794 -0.1778)
							(mid 0.249642 -0.249642)
							(end 0.1778 -0.2794)
						)
					)
					(width 0)
					(fill yes)
				)
			)
		)
		(pad "2" smd custom
			(at 0 0.4445)
			(size 0.1397 0.1397)
			(layers "F.Cu" "F.Mask" "F.Paste")
			(net "IOC_UART_0_RX")
			(options
				(clearance outline)
				(anchor circle)
			)
			(primitives
				(gr_poly
					(pts
						(arc
							(start -0.1778 -0.2794)
							(mid -0.249642 -0.249642)
							(end -0.2794 -0.1778)
						)
						(arc
							(start -0.2794 0.1778)
							(mid -0.249642 0.249642)
							(end -0.1778 0.2794)
						)
						(arc
							(start 0.1778 0.2794)
							(mid 0.249642 0.249642)
							(end 0.2794 0.1778)
						)
						(arc
							(start 0.2794 -0.1778)
							(mid 0.249642 -0.249642)
							(end 0.1778 -0.2794)
						)
					)
					(width 0)
					(fill yes)
				)
			)
		)
	)
	(footprint ""
		(layer "F.Cu")
		(at 27.99588 -124.810012)
		(property "Reference" "R788"
			(at 0 0 0)
			(layer "F.SilkS")
			(hide yes)
			(effects
				(font
					(size 1.27 1.27)
				)
			)
		)
		(property "Value" "0R2J-2-GP"
			(at 0.064008 -3.993896 0)
			(unlocked yes)
			(layer "F.Fab")
			(hide yes)
			(effects
				(font
					(size 1.016 1.016)
					(thickness 0.1524)
				)
			)
		)
		(property "Device Type" "R402H16"
			(at 0.064008 -5.517896 0)
			(unlocked yes)
			(layer "F.Fab")
			(hide yes)
			(effects
				(font
					(size 1.016 1.016)
					(thickness 0.1524)
				)
			)
		)
		(duplicate_pad_numbers_are_jumpers no)
		(fp_line
			(start -0.508 -0.9398)
			(end -0.508 0.9398)
			(stroke
				(width 0.1524)
				(type default)
			)
			(layer "F.SilkS")
		)
		(fp_line
			(start 0.508 -0.9398)
			(end -0.508 -0.9398)
			(stroke
				(width 0.1524)
				(type default)
			)
			(layer "F.SilkS")
		)
		(fp_rect
			(start -0.508 0.9398)
			(end 0.508 -0.9398)
			(stroke
				(width 0)
				(type default)
			)
			(fill no)
			(layer "F.CrtYd")
		)
		(fp_rect
			(start -0.508 0.9398)
			(end 0.508 -0.9398)
			(stroke
				(width 0)
				(type default)
			)
			(fill no)
			(layer "F.Fab")
		)
		(pad "1" smd custom
			(at 0 -0.4445)
			(size 0.1397 0.1397)
			(layers "F.Cu" "F.Mask" "F.Paste")
			(net "FLA0_WP_N")
			(options
				(clearance outline)
				(anchor circle)
			)
			(primitives
				(gr_poly
					(pts
						(arc
							(start -0.1778 -0.2794)
							(mid -0.249642 -0.249642)
							(end -0.2794 -0.1778)
						)
						(arc
							(start -0.2794 0.1778)
							(mid -0.249642 0.249642)
							(end -0.1778 0.2794)
						)
						(arc
							(start 0.1778 0.2794)
							(mid 0.249642 0.249642)
							(end 0.2794 0.1778)
						)
						(arc
							(start 0.2794 -0.1778)
							(mid 0.249642 -0.249642)
							(end 0.1778 -0.2794)
						)
					)
					(width 0)
					(fill yes)
				)
			)
		)
		(pad "2" smd custom
			(at 0 0.4445)
			(size 0.1397 0.1397)
			(layers "F.Cu" "F.Mask" "F.Paste")
			(net "WP_ENABLE")
			(options
				(clearance outline)
				(anchor circle)
			)
			(primitives
				(gr_poly
					(pts
						(arc
							(start -0.1778 -0.2794)
							(mid -0.249642 -0.249642)
							(end -0.2794 -0.1778)
						)
						(arc
							(start -0.2794 0.1778)
							(mid -0.249642 0.249642)
							(end -0.1778 0.2794)
						)
						(arc
							(start 0.1778 0.2794)
							(mid 0.249642 0.249642)
							(end 0.2794 0.1778)
						)
						(arc
							(start 0.2794 -0.1778)
							(mid 0.249642 -0.249642)
							(end 0.1778 -0.2794)
						)
					)
					(width 0)
					(fill yes)
				)
			)
		)
	)
	(footprint ""
		(layer "F.Cu")
		(at 210.3755 -125.159516 180)
		(property "Reference" "C248"
			(at 0 0 180)
			(layer "F.SilkS")
			(hide yes)
			(effects
				(font
					(size 1.27 1.27)
				)
			)
		)
		(property "Value" "SC10U6D3V5KX-4GP"
			(at -0.0762 -6.1214 180)
			(unlocked yes)
			(layer "F.Fab")
			(hide yes)
			(effects
				(font
					(size 1.016 1.016)
					(thickness 0.1524)
				)
			)
		)
		(property "Device Type" "C805H58"
			(at -0.0762 -8.1534 180)
			(unlocked yes)
			(layer "F.Fab")
			(hide yes)
			(effects
				(font
					(size 1.016 1.016)
					(thickness 0.1524)
				)
			)
		)
		(duplicate_pad_numbers_are_jumpers no)
		(fp_line
			(start 0.635 0)
			(end -0.635 0)
			(stroke
				(width 0.508)
				(type default)
			)
			(layer "F.SilkS")
		)
		(fp_rect
			(start -0.9652 1.778)
			(end 0.9652 -1.778)
			(stroke
				(width 0)
				(type default)
			)
			(fill no)
			(layer "F.CrtYd")
		)
		(fp_poly
			(pts
				(xy -0.9652 -1.778) (xy 0.9652 -1.778) (xy 0.9652 1.778) (xy -0.9652 1.778)
			)
			(stroke
				(width 0)
				(type default)
			)
			(fill no)
			(layer "F.Fab")
		)
		(pad "1" smd rect
			(at 0 -0.9652 180)
			(size 1.397 1.143)
			(layers "F.Cu" "F.Mask" "F.Paste")
			(net "P1V5_OUT")
		)
		(pad "2" smd rect
			(at 0 0.9652 180)
			(size 1.397 1.143)
			(layers "F.Cu" "F.Mask" "F.Paste")
			(net "GND")
		)
	)
	(footprint ""
		(layer "F.Cu")
		(at 168.6306 -112.5728 -90)
		(property "Reference" "R528"
			(at 0 0 270)
			(layer "F.SilkS")
			(hide yes)
			(effects
				(font
					(size 1.27 1.27)
				)
			)
		)
		(property "Value" "1KR2F-3-GP"
			(at 0.064008 -3.993896 270)
			(unlocked yes)
			(layer "F.Fab")
			(hide yes)
			(effects
				(font
					(size 1.016 1.016)
					(thickness 0.1524)
				)
			)
		)
		(property "Device Type" "R402H16"
			(at 0.064008 -5.517896 270)
			(unlocked yes)
			(layer "F.Fab")
			(hide yes)
			(effects
				(font
					(size 1.016 1.016)
					(thickness 0.1524)
				)
			)
		)
		(duplicate_pad_numbers_are_jumpers no)
		(fp_line
			(start -0.508 -0.9398)
			(end -0.508 0.9398)
			(stroke
				(width 0.1524)
				(type default)
			)
			(layer "F.SilkS")
		)
		(fp_line
			(start 0.508 -0.9398)
			(end -0.508 -0.9398)
			(stroke
				(width 0.1524)
				(type default)
			)
			(layer "F.SilkS")
		)
		(fp_rect
			(start -0.508 0.9398)
			(end 0.508 -0.9398)
			(stroke
				(width 0)
				(type default)
			)
			(fill no)
			(layer "F.CrtYd")
		)
		(fp_rect
			(start -0.508 0.9398)
			(end 0.508 -0.9398)
			(stroke
				(width 0)
				(type default)
			)
			(fill no)
			(layer "F.Fab")
		)
		(pad "1" smd custom
			(at 0 -0.4445 270)
			(size 0.1397 0.1397)
			(layers "F.Cu" "F.Mask" "F.Paste")
			(net "P1V8")
			(options
				(clearance outline)
				(anchor circle)
			)
			(primitives
				(gr_poly
					(pts
						(arc
							(start -0.1778 -0.2794)
							(mid -0.249642 -0.249642)
							(end -0.2794 -0.1778)
						)
						(arc
							(start -0.2794 0.1778)
							(mid -0.249642 0.249642)
							(end -0.1778 0.2794)
						)
						(arc
							(start 0.1778 0.2794)
							(mid 0.249642 0.249642)
							(end 0.2794 0.1778)
						)
						(arc
							(start 0.2794 -0.1778)
							(mid 0.249642 -0.249642)
							(end 0.1778 -0.2794)
						)
					)
					(width 0)
					(fill yes)
				)
			)
		)
		(pad "2" smd custom
			(at 0 0.4445 270)
			(size 0.1397 0.1397)
			(layers "F.Cu" "F.Mask" "F.Paste")
			(net "GND")
			(options
				(clearance outline)
				(anchor circle)
			)
			(primitives
				(gr_poly
					(pts
						(arc
							(start -0.1778 -0.2794)
							(mid -0.249642 -0.249642)
							(end -0.2794 -0.1778)
						)
						(arc
							(start -0.2794 0.1778)
							(mid -0.249642 0.249642)
							(end -0.1778 0.2794)
						)
						(arc
							(start 0.1778 0.2794)
							(mid 0.249642 0.249642)
							(end 0.2794 0.1778)
						)
						(arc
							(start 0.2794 -0.1778)
							(mid 0.249642 -0.249642)
							(end 0.1778 -0.2794)
						)
					)
					(width 0)
					(fill yes)
				)
			)
		)
	)
	(footprint ""
		(layer "F.Cu")
		(at 21.492464 -14.64945 180)
		(property "Reference" "C26"
			(at 0 0 180)
			(layer "F.SilkS")
			(hide yes)
			(effects
				(font
					(size 1.27 1.27)
				)
			)
		)
		(property "Value" "SC1U16V3KX-5GP"
			(at 0 -2.8194 180)
			(unlocked yes)
			(layer "F.Fab")
			(hide yes)
			(effects
				(font
					(size 1.016 1.016)
					(thickness 0.1524)
				)
			)
		)
		(property "Device Type" "C603H36"
			(at 0 -4.3434 180)
			(unlocked yes)
			(layer "F.Fab")
			(hide yes)
			(effects
				(font
					(size 1.016 1.016)
					(thickness 0.1524)
				)
			)
		)
		(duplicate_pad_numbers_are_jumpers no)
		(fp_line
			(start 0.508 0)
			(end -0.508 0)
			(stroke
				(width 0.2032)
				(type default)
			)
			(layer "F.SilkS")
		)
		(fp_rect
			(start -0.5842 1.3335)
			(end 0.5842 -1.3335)
			(stroke
				(width 0)
				(type default)
			)
			(fill no)
			(layer "F.CrtYd")
		)
		(fp_rect
			(start -0.5842 1.3335)
			(end 0.5842 -1.3335)
			(stroke
				(width 0)
				(type default)
			)
			(fill no)
			(layer "F.Fab")
		)
		(pad "1" smd custom
			(at 0 -0.762 180)
			(size 0.2159 0.2159)
			(layers "F.Cu" "F.Mask" "F.Paste")
			(net "FP_PWR_BTN_N")
			(options
				(clearance outline)
				(anchor circle)
			)
			(primitives
				(gr_poly
					(pts
						(arc
							(start -0.3302 -0.4318)
							(mid -0.402042 -0.402042)
							(end -0.4318 -0.3302)
						)
						(arc
							(start -0.4318 0.3302)
							(mid -0.402042 0.402042)
							(end -0.3302 0.4318)
						)
						(arc
							(start 0.3302 0.4318)
							(mid 0.402042 0.402042)
							(end 0.4318 0.3302)
						)
						(arc
							(start 0.4318 -0.3302)
							(mid 0.402042 -0.402042)
							(end 0.3302 -0.4318)
						)
					)
					(width 0)
					(fill yes)
				)
			)
		)
		(pad "2" smd custom
			(at 0 0.762 180)
			(size 0.2159 0.2159)
			(layers "F.Cu" "F.Mask" "F.Paste")
			(net "GND")
			(options
				(clearance outline)
				(anchor circle)
			)
			(primitives
				(gr_poly
					(pts
						(arc
							(start -0.3302 -0.4318)
							(mid -0.402042 -0.402042)
							(end -0.4318 -0.3302)
						)
						(arc
							(start -0.4318 0.3302)
							(mid -0.402042 0.402042)
							(end -0.3302 0.4318)
						)
						(arc
							(start 0.3302 0.4318)
							(mid 0.402042 0.402042)
							(end 0.4318 0.3302)
						)
						(arc
							(start 0.4318 -0.3302)
							(mid 0.402042 -0.402042)
							(end 0.3302 -0.4318)
						)
					)
					(width 0)
					(fill yes)
				)
			)
		)
	)
	(footprint ""
		(layer "F.Cu")
		(at 51.2826 -125.8824 -90)
		(property "Reference" "R599"
			(at 0 0 270)
			(layer "F.SilkS")
			(hide yes)
			(effects
				(font
					(size 1.27 1.27)
				)
			)
		)
		(property "Value" "4K7R2F-GP"
			(at 0.064008 -3.993896 270)
			(unlocked yes)
			(layer "F.Fab")
			(hide yes)
			(effects
				(font
					(size 1.016 1.016)
					(thickness 0.1524)
				)
			)
		)
		(property "Device Type" "R402H16"
			(at 0.064008 -5.517896 270)
			(unlocked yes)
			(layer "F.Fab")
			(hide yes)
			(effects
				(font
					(size 1.016 1.016)
					(thickness 0.1524)
				)
			)
		)
		(duplicate_pad_numbers_are_jumpers no)
		(fp_line
			(start -0.508 -0.9398)
			(end -0.508 0.9398)
			(stroke
				(width 0.1524)
				(type default)
			)
			(layer "F.SilkS")
		)
		(fp_line
			(start 0.508 -0.9398)
			(end -0.508 -0.9398)
			(stroke
				(width 0.1524)
				(type default)
			)
			(layer "F.SilkS")
		)
		(fp_rect
			(start -0.508 0.9398)
			(end 0.508 -0.9398)
			(stroke
				(width 0)
				(type default)
			)
			(fill no)
			(layer "F.CrtYd")
		)
		(fp_rect
			(start -0.508 0.9398)
			(end 0.508 -0.9398)
			(stroke
				(width 0)
				(type default)
			)
			(fill no)
			(layer "F.Fab")
		)
		(pad "1" smd custom
			(at 0 -0.4445 270)
			(size 0.1397 0.1397)
			(layers "F.Cu" "F.Mask" "F.Paste")
			(net "P3V3_STBY")
			(options
				(clearance outline)
				(anchor circle)
			)
			(primitives
				(gr_poly
					(pts
						(arc
							(start -0.1778 -0.2794)
							(mid -0.249642 -0.249642)
							(end -0.2794 -0.1778)
						)
						(arc
							(start -0.2794 0.1778)
							(mid -0.249642 0.249642)
							(end -0.1778 0.2794)
						)
						(arc
							(start 0.1778 0.2794)
							(mid 0.249642 0.249642)
							(end 0.2794 0.1778)
						)
						(arc
							(start 0.2794 -0.1778)
							(mid 0.249642 -0.249642)
							(end 0.1778 -0.2794)
						)
					)
					(width 0)
					(fill yes)
				)
			)
		)
		(pad "2" smd custom
			(at 0 0.4445 270)
			(size 0.1397 0.1397)
			(layers "F.Cu" "F.Mask" "F.Paste")
			(net "DPB_MISC_ALERT_OUT")
			(options
				(clearance outline)
				(anchor circle)
			)
			(primitives
				(gr_poly
					(pts
						(arc
							(start -0.1778 -0.2794)
							(mid -0.249642 -0.249642)
							(end -0.2794 -0.1778)
						)
						(arc
							(start -0.2794 0.1778)
							(mid -0.249642 0.249642)
							(end -0.1778 0.2794)
						)
						(arc
							(start 0.1778 0.2794)
							(mid 0.249642 0.249642)
							(end 0.2794 0.1778)
						)
						(arc
							(start 0.2794 -0.1778)
							(mid 0.249642 -0.249642)
							(end 0.1778 -0.2794)
						)
					)
					(width 0)
					(fill yes)
				)
			)
		)
	)
)
